(kicad_pcb
	(version 20260206)
	(generator "pcbnew")
	(generator_version "10.0")
	(general
		(thickness 1.6)
		(legacy_teardrops no)
	)
	(paper "A4")
	(title_block
		(title "01162023_DA0F0TEBIF0_F0T_Expander_BD_F_brd_V02_OCP.brd")
		(comment 1 "Grand Teton / footprints 9373-9382 of 9728")
	)
	(layers
		(0 "F.Cu" signal "TOP")
		(4 "In1.Cu" signal "GND")
		(6 "In2.Cu" signal "VCC")
		(8 "In3.Cu" signal "VCC1")
		(10 "In4.Cu" signal "GND1")
		(12 "In5.Cu" signal "IN1")
		(14 "In6.Cu" signal "GND2")
		(16 "In7.Cu" signal "IN2")
		(18 "In8.Cu" signal "GND3")
		(20 "In9.Cu" signal "IN3")
		(22 "In10.Cu" signal "GND4")
		(24 "In11.Cu" signal "IN4")
		(26 "In12.Cu" signal "GND5")
		(28 "In13.Cu" signal "IN5")
		(30 "In14.Cu" signal "GND6")
		(32 "In15.Cu" signal "IN6")
		(34 "In16.Cu" signal "GND7")
		(2 "B.Cu" signal "BOTTOM")
		(9 "F.Adhes" user "F.Adhesive")
		(11 "B.Adhes" user "B.Adhesive")
		(13 "F.Paste" user "Package Geometry/Pastemask Top")
		(15 "B.Paste" user "Package Geometry/Pastemask Bottom")
		(5 "F.SilkS" user "Ref Des/Silkscreen Top")
		(7 "B.SilkS" user "Ref Des/Silkscreen Bottom")
		(1 "F.Mask" user "Board Geometry/Soldermask Top")
		(3 "B.Mask" user "Board Geometry/Soldermask Bottom")
		(17 "Dwgs.User" user "User.Drawings")
		(19 "Cmts.User" user "User.Comments")
		(21 "Eco1.User" user "User.Eco1")
		(23 "Eco2.User" user "User.Eco2")
		(25 "Edge.Cuts" user "Board Geometry/Outline")
		(27 "Margin" user)
		(31 "F.CrtYd" user "Package Geometry/Place Bound Top")
		(29 "B.CrtYd" user "Package Geometry/Place Bound Bottom")
		(35 "F.Fab" user "Ref Des/Assembly Top")
		(33 "B.Fab" user "Ref Des/Assembly Bottom")
	)
	(footprint ""
		(layer "B.Cu")
		(at 177.174906 -305.399948 -90)
		(property "Reference" "C3143"
			(at 0 0 90)
			(layer "B.SilkS")
			(hide yes)
			(effects
				(font
					(size 1.27 1.27)
				)
				(justify mirror)
			)
		)
		(property "Value" ""
			(at 0 0 90)
			(layer "B.Fab")
			(effects
				(font
					(size 1.27 1.27)
				)
				(justify mirror)
			)
		)
		(duplicate_pad_numbers_are_jumpers no)
		(fp_line
			(start -0.299974 0.150114)
			(end 0.299974 0.150114)
			(stroke
				(width 0.1)
				(type default)
			)
			(layer "B.Fab")
		)
		(fp_line
			(start 0.299974 0.150114)
			(end 0.299974 -0.150114)
			(stroke
				(width 0.1)
				(type default)
			)
			(layer "B.Fab")
		)
		(fp_line
			(start -0.299974 -0.150114)
			(end -0.299974 0.150114)
			(stroke
				(width 0.1)
				(type default)
			)
			(layer "B.Fab")
		)
		(fp_line
			(start 0.299974 -0.150114)
			(end -0.299974 -0.150114)
			(stroke
				(width 0.1)
				(type default)
			)
			(layer "B.Fab")
		)
		(pad "1" smd rect
			(at 0.2667 0 90)
			(size 0.3048 0.381)
			(layers "B.Cu" "B.Mask" "B.Paste")
			(net "P1V25_SERDES_VDDPLL_PEX1")
		)
		(pad "2" smd rect
			(at -0.2667 0 90)
			(size 0.3048 0.381)
			(layers "B.Cu" "B.Mask" "B.Paste")
			(net "GND")
		)
	)
	(footprint ""
		(layer "B.Cu")
		(at 293.74973 -301.599854 -90)
		(property "Reference" "C1735"
			(at 0 0 90)
			(layer "B.SilkS")
			(hide yes)
			(effects
				(font
					(size 1.27 1.27)
				)
				(justify mirror)
			)
		)
		(property "Value" ""
			(at 0 0 90)
			(layer "B.Fab")
			(effects
				(font
					(size 1.27 1.27)
				)
				(justify mirror)
			)
		)
		(duplicate_pad_numbers_are_jumpers no)
		(fp_line
			(start -0.299974 0.150114)
			(end 0.299974 0.150114)
			(stroke
				(width 0.1)
				(type default)
			)
			(layer "B.Fab")
		)
		(fp_line
			(start 0.299974 0.150114)
			(end 0.299974 -0.150114)
			(stroke
				(width 0.1)
				(type default)
			)
			(layer "B.Fab")
		)
		(fp_line
			(start -0.299974 -0.150114)
			(end -0.299974 0.150114)
			(stroke
				(width 0.1)
				(type default)
			)
			(layer "B.Fab")
		)
		(fp_line
			(start 0.299974 -0.150114)
			(end -0.299974 -0.150114)
			(stroke
				(width 0.1)
				(type default)
			)
			(layer "B.Fab")
		)
		(pad "1" smd rect
			(at 0.2667 0 90)
			(size 0.3048 0.381)
			(layers "B.Cu" "B.Mask" "B.Paste")
			(net "P0V8_SERDES_VDDA_PEX2")
		)
		(pad "2" smd rect
			(at -0.2667 0 90)
			(size 0.3048 0.381)
			(layers "B.Cu" "B.Mask" "B.Paste")
			(net "GND")
		)
	)
	(footprint ""
		(layer "B.Cu")
		(at 413.649922 -301.599854 -90)
		(property "Reference" "C1946"
			(at 0 0 90)
			(layer "B.SilkS")
			(hide yes)
			(effects
				(font
					(size 1.27 1.27)
				)
				(justify mirror)
			)
		)
		(property "Value" ""
			(at 0 0 90)
			(layer "B.Fab")
			(effects
				(font
					(size 1.27 1.27)
				)
				(justify mirror)
			)
		)
		(duplicate_pad_numbers_are_jumpers no)
		(fp_line
			(start -0.299974 0.150114)
			(end 0.299974 0.150114)
			(stroke
				(width 0.1)
				(type default)
			)
			(layer "B.Fab")
		)
		(fp_line
			(start 0.299974 0.150114)
			(end 0.299974 -0.150114)
			(stroke
				(width 0.1)
				(type default)
			)
			(layer "B.Fab")
		)
		(fp_line
			(start -0.299974 -0.150114)
			(end -0.299974 0.150114)
			(stroke
				(width 0.1)
				(type default)
			)
			(layer "B.Fab")
		)
		(fp_line
			(start 0.299974 -0.150114)
			(end -0.299974 -0.150114)
			(stroke
				(width 0.1)
				(type default)
			)
			(layer "B.Fab")
		)
		(pad "1" smd rect
			(at 0.2667 0 90)
			(size 0.3048 0.381)
			(layers "B.Cu" "B.Mask" "B.Paste")
			(net "P0V8_SERDES_VDDA_PEX3")
		)
		(pad "2" smd rect
			(at -0.2667 0 90)
			(size 0.3048 0.381)
			(layers "B.Cu" "B.Mask" "B.Paste")
			(net "GND")
		)
	)
	(footprint ""
		(layer "B.Cu")
		(at 63.449962 -303.499774 -90)
		(property "Reference" "C2910"
			(at 0 0 90)
			(layer "B.SilkS")
			(hide yes)
			(effects
				(font
					(size 1.27 1.27)
				)
				(justify mirror)
			)
		)
		(property "Value" ""
			(at 0 0 90)
			(layer "B.Fab")
			(effects
				(font
					(size 1.27 1.27)
				)
				(justify mirror)
			)
		)
		(duplicate_pad_numbers_are_jumpers no)
		(fp_line
			(start -0.299974 0.150114)
			(end 0.299974 0.150114)
			(stroke
				(width 0.1)
				(type default)
			)
			(layer "B.Fab")
		)
		(fp_line
			(start 0.299974 0.150114)
			(end 0.299974 -0.150114)
			(stroke
				(width 0.1)
				(type default)
			)
			(layer "B.Fab")
		)
		(fp_line
			(start -0.299974 -0.150114)
			(end -0.299974 0.150114)
			(stroke
				(width 0.1)
				(type default)
			)
			(layer "B.Fab")
		)
		(fp_line
			(start 0.299974 -0.150114)
			(end -0.299974 -0.150114)
			(stroke
				(width 0.1)
				(type default)
			)
			(layer "B.Fab")
		)
		(pad "1" smd rect
			(at 0.2667 0 90)
			(size 0.3048 0.381)
			(layers "B.Cu" "B.Mask" "B.Paste")
			(net "P1V25_PEX0")
		)
		(pad "2" smd rect
			(at -0.2667 0 90)
			(size 0.3048 0.381)
			(layers "B.Cu" "B.Mask" "B.Paste")
			(net "GND")
		)
	)
	(footprint ""
		(layer "B.Cu")
		(at 309.741824 -95.989648 180)
		(property "Reference" "R266"
			(at 0 0 0)
			(layer "B.SilkS")
			(hide yes)
			(effects
				(font
					(size 1.27 1.27)
				)
				(justify mirror)
			)
		)
		(property "Value" ""
			(at 0 0 0)
			(layer "B.Fab")
			(effects
				(font
					(size 1.27 1.27)
				)
				(justify mirror)
			)
		)
		(duplicate_pad_numbers_are_jumpers no)
		(fp_line
			(start 0.7874 0.4064)
			(end 0.7874 -0.4064)
			(stroke
				(width 0.1524)
				(type default)
			)
			(layer "B.SilkS")
		)
		(fp_line
			(start 0.7874 -0.4064)
			(end -0.7874 -0.4064)
			(stroke
				(width 0.1524)
				(type default)
			)
			(layer "B.SilkS")
		)
		(fp_line
			(start -0.7874 0.4064)
			(end 0.7874 0.4064)
			(stroke
				(width 0.1524)
				(type default)
			)
			(layer "B.SilkS")
		)
		(fp_line
			(start -0.7874 -0.4064)
			(end -0.7874 0.4064)
			(stroke
				(width 0.1524)
				(type default)
			)
			(layer "B.SilkS")
		)
		(fp_line
			(start 0.67945 0.3048)
			(end 0.67945 -0.305054)
			(stroke
				(width 0.1)
				(type default)
			)
			(layer "B.Fab")
		)
		(fp_line
			(start 0.67945 -0.305054)
			(end 0.12065 -0.305054)
			(stroke
				(width 0.1)
				(type default)
			)
			(layer "B.Fab")
		)
		(fp_line
			(start 0.12065 0.3048)
			(end 0.67945 0.3048)
			(stroke
				(width 0.1)
				(type default)
			)
			(layer "B.Fab")
		)
		(fp_line
			(start 0.12065 0.2794)
			(end 0.12065 0.3048)
			(stroke
				(width 0.1)
				(type default)
			)
			(layer "B.Fab")
		)
		(fp_line
			(start 0.12065 -0.2794)
			(end -0.12065 -0.2794)
			(stroke
				(width 0.1)
				(type default)
			)
			(layer "B.Fab")
		)
		(fp_line
			(start 0.12065 -0.305054)
			(end 0.12065 -0.2794)
			(stroke
				(width 0.1)
				(type default)
			)
			(layer "B.Fab")
		)
		(fp_line
			(start -0.120396 0.3048)
			(end -0.120396 0.2794)
			(stroke
				(width 0.1)
				(type default)
			)
			(layer "B.Fab")
		)
		(fp_line
			(start -0.120396 0.2794)
			(end 0.12065 0.2794)
			(stroke
				(width 0.1)
				(type default)
			)
			(layer "B.Fab")
		)
		(fp_line
			(start -0.12065 -0.2794)
			(end -0.12065 -0.3048)
			(stroke
				(width 0.1)
				(type default)
			)
			(layer "B.Fab")
		)
		(fp_line
			(start -0.12065 -0.3048)
			(end -0.67945 -0.3048)
			(stroke
				(width 0.1)
				(type default)
			)
			(layer "B.Fab")
		)
		(fp_line
			(start -0.67945 0.3048)
			(end -0.120396 0.3048)
			(stroke
				(width 0.1)
				(type default)
			)
			(layer "B.Fab")
		)
		(fp_line
			(start -0.67945 -0.3048)
			(end -0.67945 0.3048)
			(stroke
				(width 0.1)
				(type default)
			)
			(layer "B.Fab")
		)
		(pad "1" smd circle
			(at 0.40005 0)
			(size 0 0)
			(layers "B.Cu" "B.Mask" "B.Paste")
			(net "NIC5_LD_N")
		)
		(pad "2" smd circle
			(at -0.40005 0)
			(size 0 0)
			(layers "B.Cu" "B.Mask" "B.Paste")
			(net "P3V3_NIC5")
		)
	)
	(footprint ""
		(layer "B.Cu")
		(at 307.923692 -291.624766 90)
		(property "Reference" "R996"
			(at 0 0 90)
			(layer "B.SilkS")
			(hide yes)
			(effects
				(font
					(size 1.27 1.27)
				)
				(justify mirror)
			)
		)
		(property "Value" ""
			(at 0 0 90)
			(layer "B.Fab")
			(effects
				(font
					(size 1.27 1.27)
				)
				(justify mirror)
			)
		)
		(duplicate_pad_numbers_are_jumpers no)
		(fp_line
			(start 0.7874 -0.4064)
			(end -0.7874 -0.4064)
			(stroke
				(width 0.1524)
				(type default)
			)
			(layer "B.SilkS")
		)
		(fp_line
			(start -0.7874 -0.4064)
			(end -0.7874 0.4064)
			(stroke
				(width 0.1524)
				(type default)
			)
			(layer "B.SilkS")
		)
		(fp_line
			(start 0.7874 0.4064)
			(end 0.7874 -0.4064)
			(stroke
				(width 0.1524)
				(type default)
			)
			(layer "B.SilkS")
		)
		(fp_line
			(start -0.7874 0.4064)
			(end 0.7874 0.4064)
			(stroke
				(width 0.1524)
				(type default)
			)
			(layer "B.SilkS")
		)
		(fp_line
			(start 0.67945 -0.305054)
			(end 0.12065 -0.305054)
			(stroke
				(width 0.1)
				(type default)
			)
			(layer "B.Fab")
		)
		(fp_line
			(start 0.12065 -0.305054)
			(end 0.12065 -0.2794)
			(stroke
				(width 0.1)
				(type default)
			)
			(layer "B.Fab")
		)
		(fp_line
			(start -0.12065 -0.3048)
			(end -0.67945 -0.3048)
			(stroke
				(width 0.1)
				(type default)
			)
			(layer "B.Fab")
		)
		(fp_line
			(start -0.67945 -0.3048)
			(end -0.67945 0.3048)
			(stroke
				(width 0.1)
				(type default)
			)
			(layer "B.Fab")
		)
		(fp_line
			(start 0.12065 -0.2794)
			(end -0.12065 -0.2794)
			(stroke
				(width 0.1)
				(type default)
			)
			(layer "B.Fab")
		)
		(fp_line
			(start -0.12065 -0.2794)
			(end -0.12065 -0.3048)
			(stroke
				(width 0.1)
				(type default)
			)
			(layer "B.Fab")
		)
		(fp_line
			(start 0.12065 0.2794)
			(end 0.12065 0.3048)
			(stroke
				(width 0.1)
				(type default)
			)
			(layer "B.Fab")
		)
		(fp_line
			(start -0.120396 0.2794)
			(end 0.12065 0.2794)
			(stroke
				(width 0.1)
				(type default)
			)
			(layer "B.Fab")
		)
		(fp_line
			(start 0.67945 0.3048)
			(end 0.67945 -0.305054)
			(stroke
				(width 0.1)
				(type default)
			)
			(layer "B.Fab")
		)
		(fp_line
			(start 0.12065 0.3048)
			(end 0.67945 0.3048)
			(stroke
				(width 0.1)
				(type default)
			)
			(layer "B.Fab")
		)
		(fp_line
			(start -0.120396 0.3048)
			(end -0.120396 0.2794)
			(stroke
				(width 0.1)
				(type default)
			)
			(layer "B.Fab")
		)
		(fp_line
			(start -0.67945 0.3048)
			(end -0.120396 0.3048)
			(stroke
				(width 0.1)
				(type default)
			)
			(layer "B.Fab")
		)
		(pad "1" smd circle
			(at 0.40005 0 270)
			(size 0 0)
			(layers "B.Cu" "B.Mask" "B.Paste")
			(net "UART_PEX2_CLI_TX")
		)
		(pad "2" smd circle
			(at -0.40005 0 270)
			(size 0 0)
			(layers "B.Cu" "B.Mask" "B.Paste")
			(net "UART_PEX2_CLI_R_TX")
		)
	)
	(footprint ""
		(layer "B.Cu")
		(at 104.960674 -284.796738 -90)
		(property "Reference" "PC77"
			(at 0 0 90)
			(layer "B.SilkS")
			(hide yes)
			(effects
				(font
					(size 1.27 1.27)
				)
				(justify mirror)
			)
		)
		(property "Value" ""
			(at 0 0 90)
			(layer "B.Fab")
			(effects
				(font
					(size 1.27 1.27)
				)
				(justify mirror)
			)
		)
		(duplicate_pad_numbers_are_jumpers no)
		(fp_line
			(start -1.524 0.762)
			(end 1.524 0.762)
			(stroke
				(width 0.1524)
				(type default)
			)
			(layer "B.SilkS")
		)
		(fp_line
			(start 1.524 0.762)
			(end 1.524 -0.762)
			(stroke
				(width 0.1524)
				(type default)
			)
			(layer "B.SilkS")
		)
		(fp_line
			(start -1.524 -0.762)
			(end -1.524 0.762)
			(stroke
				(width 0.1524)
				(type default)
			)
			(layer "B.SilkS")
		)
		(fp_line
			(start 1.524 -0.762)
			(end -1.524 -0.762)
			(stroke
				(width 0.1524)
				(type default)
			)
			(layer "B.SilkS")
		)
		(fp_line
			(start -1.1049 0.724916)
			(end -1.1049 -0.724916)
			(stroke
				(width 0.1)
				(type default)
			)
			(layer "B.Fab")
		)
		(fp_line
			(start 1.1049 0.724916)
			(end -1.1049 0.724916)
			(stroke
				(width 0.1)
				(type default)
			)
			(layer "B.Fab")
		)
		(fp_line
			(start -1.1049 -0.724916)
			(end 1.1049 -0.724916)
			(stroke
				(width 0.1)
				(type default)
			)
			(layer "B.Fab")
		)
		(fp_line
			(start 1.1049 -0.724916)
			(end 1.1049 0.724916)
			(stroke
				(width 0.1)
				(type default)
			)
			(layer "B.Fab")
		)
		(pad "1" smd rect
			(at 0.889 0 270)
			(size 1.016 1.27)
			(layers "B.Cu" "B.Mask" "B.Paste")
			(net "SW_P12V_P0V8_PEX0_FLT")
		)
		(pad "2" smd rect
			(at -0.889 0 270)
			(size 1.016 1.27)
			(layers "B.Cu" "B.Mask" "B.Paste")
			(net "GND")
		)
	)
	(footprint ""
		(layer "B.Cu")
		(at 452.08444 -286.034988)
		(property "Reference" "PC275"
			(at 0 0 0)
			(layer "B.SilkS")
			(hide yes)
			(effects
				(font
					(size 1.27 1.27)
				)
				(justify mirror)
			)
		)
		(property "Value" ""
			(at 0 0 0)
			(layer "B.Fab")
			(effects
				(font
					(size 1.27 1.27)
				)
				(justify mirror)
			)
		)
		(duplicate_pad_numbers_are_jumpers no)
		(fp_line
			(start -1.524 -0.762)
			(end -1.524 0.762)
			(stroke
				(width 0.1524)
				(type default)
			)
			(layer "B.SilkS")
		)
		(fp_line
			(start -1.524 0.762)
			(end 1.524 0.762)
			(stroke
				(width 0.1524)
				(type default)
			)
			(layer "B.SilkS")
		)
		(fp_line
			(start 1.524 -0.762)
			(end -1.524 -0.762)
			(stroke
				(width 0.1524)
				(type default)
			)
			(layer "B.SilkS")
		)
		(fp_line
			(start 1.524 0.762)
			(end 1.524 -0.762)
			(stroke
				(width 0.1524)
				(type default)
			)
			(layer "B.SilkS")
		)
		(fp_line
			(start -1.1049 -0.724916)
			(end 1.1049 -0.724916)
			(stroke
				(width 0.1)
				(type default)
			)
			(layer "B.Fab")
		)
		(fp_line
			(start -1.1049 0.724916)
			(end -1.1049 -0.724916)
			(stroke
				(width 0.1)
				(type default)
			)
			(layer "B.Fab")
		)
		(fp_line
			(start 1.1049 -0.724916)
			(end 1.1049 0.724916)
			(stroke
				(width 0.1)
				(type default)
			)
			(layer "B.Fab")
		)
		(fp_line
			(start 1.1049 0.724916)
			(end -1.1049 0.724916)
			(stroke
				(width 0.1)
				(type default)
			)
			(layer "B.Fab")
		)
		(pad "1" smd rect
			(at 0.889 0)
			(size 1.016 1.27)
			(layers "B.Cu" "B.Mask" "B.Paste")
			(net "P1V25_PEX3_R")
		)
		(pad "2" smd rect
			(at -0.889 0)
			(size 1.016 1.27)
			(layers "B.Cu" "B.Mask" "B.Paste")
			(net "GND")
		)
	)
	(footprint ""
		(layer "B.Cu")
		(at 45.864272 -144.421352 180)
		(property "Reference" "C849"
			(at 0 0 0)
			(layer "B.SilkS")
			(hide yes)
			(effects
				(font
					(size 1.27 1.27)
				)
				(justify mirror)
			)
		)
		(property "Value" ""
			(at 0 0 0)
			(layer "B.Fab")
			(effects
				(font
					(size 1.27 1.27)
				)
				(justify mirror)
			)
		)
		(duplicate_pad_numbers_are_jumpers no)
		(fp_line
			(start 0.299974 0.150114)
			(end 0.299974 -0.150114)
			(stroke
				(width 0.1)
				(type default)
			)
			(layer "B.Fab")
		)
		(fp_line
			(start 0.299974 -0.150114)
			(end -0.299974 -0.150114)
			(stroke
				(width 0.1)
				(type default)
			)
			(layer "B.Fab")
		)
		(fp_line
			(start -0.299974 0.150114)
			(end 0.299974 0.150114)
			(stroke
				(width 0.1)
				(type default)
			)
			(layer "B.Fab")
		)
		(fp_line
			(start -0.299974 -0.150114)
			(end -0.299974 0.150114)
			(stroke
				(width 0.1)
				(type default)
			)
			(layer "B.Fab")
		)
		(pad "1" smd rect
			(at 0.2667 0)
			(size 0.3048 0.381)
			(layers "B.Cu" "B.Mask" "B.Paste")
			(net "P12V_NIC0")
		)
		(pad "2" smd rect
			(at -0.2667 0)
			(size 0.3048 0.381)
			(layers "B.Cu" "B.Mask" "B.Paste")
			(net "GND")
		)
	)
	(footprint ""
		(layer "B.Cu")
		(at 110.694216 -137.56386 90)
		(property "Reference" "PC34"
			(at 0 0 90)
			(layer "B.SilkS")
			(hide yes)
			(effects
				(font
					(size 1.27 1.27)
				)
				(justify mirror)
			)
		)
		(property "Value" ""
			(at 0 0 90)
			(layer "B.Fab")
			(effects
				(font
					(size 1.27 1.27)
				)
				(justify mirror)
			)
		)
		(duplicate_pad_numbers_are_jumpers no)
		(fp_line
			(start 1.524 -0.762)
			(end -1.524 -0.762)
			(stroke
				(width 0.1524)
				(type default)
			)
			(layer "B.SilkS")
		)
		(fp_line
			(start -1.524 -0.762)
			(end -1.524 0.762)
			(stroke
				(width 0.1524)
				(type default)
			)
			(layer "B.SilkS")
		)
		(fp_line
			(start 1.524 0.762)
			(end 1.524 -0.762)
			(stroke
				(width 0.1524)
				(type default)
			)
			(layer "B.SilkS")
		)
		(fp_line
			(start -1.524 0.762)
			(end 1.524 0.762)
			(stroke
				(width 0.1524)
				(type default)
			)
			(layer "B.SilkS")
		)
		(fp_line
			(start 1.1049 -0.724916)
			(end 1.1049 0.724916)
			(stroke
				(width 0.1)
				(type default)
			)
			(layer "B.Fab")
		)
		(fp_line
			(start -1.1049 -0.724916)
			(end 1.1049 -0.724916)
			(stroke
				(width 0.1)
				(type default)
			)
			(layer "B.Fab")
		)
		(fp_line
			(start 1.1049 0.724916)
			(end -1.1049 0.724916)
			(stroke
				(width 0.1)
				(type default)
			)
			(layer "B.Fab")
		)
		(fp_line
			(start -1.1049 0.724916)
			(end -1.1049 -0.724916)
			(stroke
				(width 0.1)
				(type default)
			)
			(layer "B.Fab")
		)
		(pad "1" smd rect
			(at 0.889 0 90)
			(size 1.016 1.27)
			(layers "B.Cu" "B.Mask" "B.Paste")
			(net "P3V3_AUX")
		)
		(pad "2" smd rect
			(at -0.889 0 90)
			(size 1.016 1.27)
			(layers "B.Cu" "B.Mask" "B.Paste")
			(net "GND")
		)
	)
)
